# T6G (Grand Teton) — schematic netlist excerpt (pin names and nets, part order shuffled) for the footprints in the layout excerpt that follows; sources: Cadence DE-HDL packaged netlist, KiCad conversion of 04192023_DAF0TMB3IC0_F0TG_MB_C_brd_V02_OCP.brd

R1177  Q_RES  33.2 1% CHIP  pkg 0402LF  page 142 : A = RST_PERST_OCP_V3_2_BUF_R_N ; B = RST_PERST_OCP_V3_2_BUF_N
R1552  Q_RES  33 5% CHIP  pkg 0402LF  page 81 : A = ESPI_CPU0_R1_D3 ; B = ESPI_CPU0_D3

(kicad_pcb
	(version 20260206)
	(generator "pcbnew")
	(generator_version "10.0")
	(general
		(thickness 1.6)
		(legacy_teardrops no)
	)
	(paper "A4")
	(title_block
		(title "04192023_DAF0TMB3IC0_F0TG_MB_C_brd_V02_OCP.brd")
		(comment 1 "Grand Teton / footprints 4149-4150 of 8354")
	)
	(layers
		(0 "F.Cu" signal "TOP")
		(4 "In1.Cu" signal "GND")
		(6 "In2.Cu" signal "IN1")
		(8 "In3.Cu" signal "GND1")
		(10 "In4.Cu" signal "IN2")
		(12 "In5.Cu" signal "GND2")
		(14 "In6.Cu" signal "IN3")
		(16 "In7.Cu" signal "GND3")
		(18 "In8.Cu" signal "VCC")
		(20 "In9.Cu" signal "VCC1")
		(22 "In10.Cu" signal "GND4")
		(24 "In11.Cu" signal "IN4")
		(26 "In12.Cu" signal "GND5")
		(28 "In13.Cu" signal "IN5")
		(30 "In14.Cu" signal "GND6")
		(32 "In15.Cu" signal "IN6")
		(34 "In16.Cu" signal "GND7")
		(2 "B.Cu" signal "BOTTOM")
		(9 "F.Adhes" user "F.Adhesive")
		(11 "B.Adhes" user "B.Adhesive")
		(13 "F.Paste" user "Package Geometry/Pastemask Top")
		(15 "B.Paste" user "Package Geometry/Pastemask Bottom")
		(5 "F.SilkS" user "Ref Des/Silkscreen Top")
		(7 "B.SilkS" user "Ref Des/Silkscreen Bottom")
		(1 "F.Mask" user "Board Geometry/Soldermask Top")
		(3 "B.Mask" user "Board Geometry/Soldermask Bottom")
		(17 "Dwgs.User" user "User.Drawings")
		(19 "Cmts.User" user "User.Comments")
		(21 "Eco1.User" user "User.Eco1")
		(23 "Eco2.User" user "User.Eco2")
		(25 "Edge.Cuts" user "Board Geometry/Outline")
		(27 "Margin" user)
		(31 "F.CrtYd" user "Package Geometry/Place Bound Top")
		(29 "B.CrtYd" user "Package Geometry/Place Bound Bottom")
		(35 "F.Fab" user "Ref Des/Assembly Top")
		(33 "B.Fab" user "Ref Des/Assembly Bottom")
	)
	(footprint ""
		(layer "F.Cu")
		(at 73.303638 -55.122826 -90)
		(property "Reference" "R1177"
			(at 0 0 270)
			(layer "F.SilkS")
			(hide yes)
			(effects
				(font
					(size 1.27 1.27)
				)
			)
		)
		(property "Value" ""
			(at 0 0 270)
			(layer "F.Fab")
			(effects
				(font
					(size 1.27 1.27)
				)
			)
		)
		(duplicate_pad_numbers_are_jumpers no)
		(fp_line
			(start -0.7874 0.4064)
			(end -0.7874 -0.4064)
			(stroke
				(width 0.1524)
				(type default)
			)
			(layer "F.SilkS")
		)
		(fp_line
			(start 0.7874 0.4064)
			(end -0.7874 0.4064)
			(stroke
				(width 0.1524)
				(type default)
			)
			(layer "F.SilkS")
		)
		(fp_line
			(start -0.7874 -0.4064)
			(end 0.7874 -0.4064)
			(stroke
				(width 0.1524)
				(type default)
			)
			(layer "F.SilkS")
		)
		(fp_line
			(start 0.7874 -0.4064)
			(end 0.7874 0.4064)
			(stroke
				(width 0.1524)
				(type default)
			)
			(layer "F.SilkS")
		)
		(fp_line
			(start -0.67945 0.3048)
			(end -0.67945 -0.305054)
			(stroke
				(width 0.1)
				(type default)
			)
			(layer "F.Fab")
		)
		(fp_line
			(start -0.12065 0.3048)
			(end -0.67945 0.3048)
			(stroke
				(width 0.1)
				(type default)
			)
			(layer "F.Fab")
		)
		(fp_line
			(start 0.120396 0.3048)
			(end 0.120396 0.2794)
			(stroke
				(width 0.1)
				(type default)
			)
			(layer "F.Fab")
		)
		(fp_line
			(start 0.67945 0.3048)
			(end 0.120396 0.3048)
			(stroke
				(width 0.1)
				(type default)
			)
			(layer "F.Fab")
		)
		(fp_line
			(start -0.12065 0.2794)
			(end -0.12065 0.3048)
			(stroke
				(width 0.1)
				(type default)
			)
			(layer "F.Fab")
		)
		(fp_line
			(start 0.120396 0.2794)
			(end -0.12065 0.2794)
			(stroke
				(width 0.1)
				(type default)
			)
			(layer "F.Fab")
		)
		(fp_line
			(start -0.12065 -0.2794)
			(end 0.12065 -0.2794)
			(stroke
				(width 0.1)
				(type default)
			)
			(layer "F.Fab")
		)
		(fp_line
			(start 0.12065 -0.2794)
			(end 0.12065 -0.3048)
			(stroke
				(width 0.1)
				(type default)
			)
			(layer "F.Fab")
		)
		(fp_line
			(start 0.12065 -0.3048)
			(end 0.67945 -0.3048)
			(stroke
				(width 0.1)
				(type default)
			)
			(layer "F.Fab")
		)
		(fp_line
			(start 0.67945 -0.3048)
			(end 0.67945 0.3048)
			(stroke
				(width 0.1)
				(type default)
			)
			(layer "F.Fab")
		)
		(fp_line
			(start -0.67945 -0.305054)
			(end -0.12065 -0.305054)
			(stroke
				(width 0.1)
				(type default)
			)
			(layer "F.Fab")
		)
		(fp_line
			(start -0.12065 -0.305054)
			(end -0.12065 -0.2794)
			(stroke
				(width 0.1)
				(type default)
			)
			(layer "F.Fab")
		)
		(pad "1" smd circle
			(at -0.40005 0 270)
			(size 0 0)
			(layers "F.Cu" "F.Mask" "F.Paste")
			(net "RST_PERST_OCP_V3_2_BUF_R_N")
		)
		(pad "2" smd circle
			(at 0.40005 0 270)
			(size 0 0)
			(layers "F.Cu" "F.Mask" "F.Paste")
			(net "RST_PERST_OCP_V3_2_BUF_N")
		)
	)
	(footprint ""
		(layer "F.Cu")
		(at 187.071 -137.632948 90)
		(property "Reference" "R1552"
			(at 0 0 90)
			(layer "F.SilkS")
			(hide yes)
			(effects
				(font
					(size 1.27 1.27)
				)
			)
		)
		(property "Value" ""
			(at 0 0 90)
			(layer "F.Fab")
			(effects
				(font
					(size 1.27 1.27)
				)
			)
		)
		(duplicate_pad_numbers_are_jumpers no)
		(fp_line
			(start 0.7874 -0.4064)
			(end 0.7874 0.4064)
			(stroke
				(width 0.1524)
				(type default)
			)
			(layer "F.SilkS")
		)
		(fp_line
			(start -0.7874 -0.4064)
			(end 0.7874 -0.4064)
			(stroke
				(width 0.1524)
				(type default)
			)
			(layer "F.SilkS")
		)
		(fp_line
			(start 0.7874 0.4064)
			(end -0.7874 0.4064)
			(stroke
				(width 0.1524)
				(type default)
			)
			(layer "F.SilkS")
		)
		(fp_line
			(start -0.7874 0.4064)
			(end -0.7874 -0.4064)
			(stroke
				(width 0.1524)
				(type default)
			)
			(layer "F.SilkS")
		)
		(fp_line
			(start -0.12065 -0.305054)
			(end -0.12065 -0.2794)
			(stroke
				(width 0.1)
				(type default)
			)
			(layer "F.Fab")
		)
		(fp_line
			(start -0.67945 -0.305054)
			(end -0.12065 -0.305054)
			(stroke
				(width 0.1)
				(type default)
			)
			(layer "F.Fab")
		)
		(fp_line
			(start 0.67945 -0.3048)
			(end 0.67945 0.3048)
			(stroke
				(width 0.1)
				(type default)
			)
			(layer "F.Fab")
		)
		(fp_line
			(start 0.12065 -0.3048)
			(end 0.67945 -0.3048)
			(stroke
				(width 0.1)
				(type default)
			)
			(layer "F.Fab")
		)
		(fp_line
			(start 0.12065 -0.2794)
			(end 0.12065 -0.3048)
			(stroke
				(width 0.1)
				(type default)
			)
			(layer "F.Fab")
		)
		(fp_line
			(start -0.12065 -0.2794)
			(end 0.12065 -0.2794)
			(stroke
				(width 0.1)
				(type default)
			)
			(layer "F.Fab")
		)
		(fp_line
			(start 0.120396 0.2794)
			(end -0.12065 0.2794)
			(stroke
				(width 0.1)
				(type default)
			)
			(layer "F.Fab")
		)
		(fp_line
			(start -0.12065 0.2794)
			(end -0.12065 0.3048)
			(stroke
				(width 0.1)
				(type default)
			)
			(layer "F.Fab")
		)
		(fp_line
			(start 0.67945 0.3048)
			(end 0.120396 0.3048)
			(stroke
				(width 0.1)
				(type default)
			)
			(layer "F.Fab")
		)
		(fp_line
			(start 0.120396 0.3048)
			(end 0.120396 0.2794)
			(stroke
				(width 0.1)
				(type default)
			)
			(layer "F.Fab")
		)
		(fp_line
			(start -0.12065 0.3048)
			(end -0.67945 0.3048)
			(stroke
				(width 0.1)
				(type default)
			)
			(layer "F.Fab")
		)
		(fp_line
			(start -0.67945 0.3048)
			(end -0.67945 -0.305054)
			(stroke
				(width 0.1)
				(type default)
			)
			(layer "F.Fab")
		)
		(pad "1" smd circle
			(at -0.40005 0 90)
			(size 0 0)
			(layers "F.Cu" "F.Mask" "F.Paste")
			(net "ESPI_CPU0_R1_D3")
		)
		(pad "2" smd circle
			(at 0.40005 0 90)
			(size 0 0)
			(layers "F.Cu" "F.Mask" "F.Paste")
			(net "ESPI_CPU0_D3")
		)
	)
)
